FILE_TYPE = CONNECTIVITY;
{Allegro Design Entry HDL 17.2-2016 S081 (4005846) 1/11/2022}
"PAGE_NUMBER" = 273;
0"NC";
1"PVCCIN_CPU1_PVCC\g";
2"PVCCIN_CPU1_PVCC\g";
3"SW_P12V_PVCCIN_CPU1_FLT\g";
4"PVCCIN_CPU1\g";
5"SW_P12V_PVCCIN_CPU1_FLT\g";
6"PVCCIN_CPU1\g";
7"GND\g";
8"GND\g";
9"GND\g";
10"GND\g";
11"GND\g";
12"GND\g";
13"GND\g";
14"GND\g";
15"GND\g";
16"GND\g";
17"GND\g";
18"GND\g";
19"GND\g";
20"GND\g";
21"IND_P1_CPL4";
22"IND_P1_CPL7";
23"IND_P1_CPL5";
24"SW_PVCCIN_CPU1_BOOT5_R";
25"SW_PVCCIN_CPU1_BOOT5"CDS_PHYS_NET_NAME"SW_PVCCIN_CPU1_BOOT5";
26"PVCCIN_CPU1_VOS5";
27"SW_PVCCIN_CPU1_SW5";
28"SW_PVCCIN_CPU1_BOOTR5"CDS_PHYS_NET_NAME"SW_PVCCIN_CPU1_BOOTR5";
29"PVCCIN_CPU1_VDD5";
30"PVCCIN_CPU1_ATSEN";
31"PVCCIN_CPU1_IMON5";
32"PVCCIN_CPU1_VREF"CDS_PHYS_NET_NAME"PVCCIN_CPU1_VREF";
33"SW_PVCCIN_CPU1_BOOT6_R";
34"SW_PVCCIN_CPU1_BOOT6"CDS_PHYS_NET_NAME"SW_PVCCIN_CPU1_BOOT6";
35"IND_P1_CPL6";
36"PVCCIN_CPU1_VOS6";
37"SW_PVCCIN_CPU1_BOOTR6"CDS_PHYS_NET_NAME"SW_PVCCIN_CPU1_BOOTR6";
38"SW_PVCCIN_CPU1_SW6";
39"PVCCIN_CPU1_PWM5";
40"PVCCIN_CPU1_VDD6";
41"PVCCIN_CPU1_ATSEN";
42"PVCCIN_CPU1_IMON6";
43"PVCCIN_CPU1_PWM6";
44"PVCCIN_CPU1_VREF"CDS_PHYS_NET_NAME"PVCCIN_CPU1_VREF";
45"PVCCIN_CPU1_LSET5";
46"PVCCIN_CPU1_LSET6";
%"UNIVERSAL_GND"
"1","(3375,-1050)","0","logical_power","I1";
;
CDS_LIB"logical_power"
HDL_POWER"GND";
"A"7;
%"Q_CAP"
"2","(4100,-525)","0","pure_quanta","I15";
;
PART_NUMBER"CH4104K1B00"
MATERIAL"X7R"
TOLERANCE"10%"
VALUE"0.1UF"
VOLTAGE"25V"
PACK_TYPE"0402"
LOCATION"PC1360"
CDS_LIB"pure_quanta"
$SEC"1"
CDS_SEC"1";
"A"
$PN"1"8;
"B"
$PN"2"44;
%"ISL99390FRZTR5935"
"1","(5300,-325)","0","pure_quanta","I16";
;
PART_NUMBER"AL099390004"
PART_TYPE"SMLF"
MATERIAL"IC"
VALUE"ISL99390FRZ-TR5935"
LOCATION"PU25_P1_6"
NEEDS_NO_SIZE"TRUE"
CDS_LMAN_SYM_OUTLINE"-300,700,250,-650"
CDS_LIB"pure_quanta"
$SEC"1"
CDS_SEC"1";
"PGND2"
$PN"7_9-20_24"13;
"GL2"
$PN"41"0;
"GL1"
$PN"6"0;
"DNC"
$PN"31"0;
"EN"
$PN"35"40;
"PGND3"
$PN"40"13;
"VOS"
$PN"1"36;
"VIN2"
$PN"30"3;
"PGND1"
$PN"5"13;
"SW"
$PN"10_19"38;
"LSET"
$PN"37"46;
"IOUT"
$PN"38"42;
"TOUT_FLT"
$PN"36"41;
"PVCC"
$PN"4"1;
"PHASE"
$PN"32"37;
"VIN1"
$PN"25_29"3;
"BOOT"
$PN"33"34;
"AGND"
$PN"2"13;
"VCC"
$PN"3"40;
"REFIN"
$PN"39"44;
"PWM"
$PN"34"43;
%"Q_CAP"
"1","(3775,175)","0","pure_quanta","I17";
;
PART_NUMBER"CH5222KEB01"
MATERIAL"X6S"
TOLERANCE"10%"
VALUE"2.2UF"
VOLTAGE"10V"
PACK_TYPE"C0402"
LOCATION"PC501"
CDS_LIB"pure_quanta"
LOCATION"PC501"
$SEC"1"
CDS_SEC"1";
"B"
$PN"2"11;
"A"
$PN"1"40;
%"UNIVERSAL_GND"
"1","(3775,-75)","0","logical_power","I18";
;
CDS_LIB"logical_power"
HDL_POWER"GND";
"A"11;
%"Q_RES"
"2","(3775,675)","0","pure_quanta","I19";
;
PART_NUMBER"CS-2202FB01"
WATTAGE"1/16W"
MATERIAL"CHIP"
TOLERANCE"1%"
VALUE"2.2"
PACK_TYPE"0402LF"
LOCATION"PR293"
CDS_LIB"pure_quanta"
LOCATION"PR293"
$SEC"1"
CDS_SEC"1";
"A"
$PN"1"1;
"B"
$PN"2"40;
%"Q_RES"
"2","(3375,-825)","2","pure_quanta","I2";
;
PART_NUMBER"CS28872FB01"
WATTAGE"1/16W"
MATERIAL"EMPTY"
TOLERANCE"1%"
VALUE"8.87K"
PACK_TYPE"0402LF"
LOCATION"PR291"
CDS_LIB"pure_quanta"
LOCATION"PR291"
$SEC"1"
CDS_SEC"1";
"A"
$PN"1"46;
"B"
$PN"2"7;
%"UNIVERSAL_GND"
"1","(4200,450)","0","logical_power","I20";
;
CDS_LIB"logical_power"
HDL_POWER"GND";
"A"12;
%"Q_CAP"
"1","(4200,675)","0","pure_quanta","I21";
;
PART_NUMBER"CH5222KEB01"
MATERIAL"X6S"
TOLERANCE"10%"
VALUE"2.2UF"
VOLTAGE"10V"
PACK_TYPE"C0402"
LOCATION"PC503_P1_6"
CDS_LIB"pure_quanta"
LOCATION"PC503_P1_6"
$SEC"1"
CDS_SEC"1";
"B"
$PN"2"12;
"A"
$PN"1"1;
%"VCC15"
"1","(3775,1000)","0","logical_power","I22";
;
HDL_POWER"PVCCIN_CPU1_PVCC"
CDS_LIB"logical_power";
"A"1;
%"ISL99390FRZTR5935"
"1","(5325,2500)","0","pure_quanta","I23";
;
PART_NUMBER"AL099390004"
PART_TYPE"SMLF"
MATERIAL"IC"
VALUE"ISL99390FRZ-TR5935"
LOCATION"PU26_P1_5"
NEEDS_NO_SIZE"TRUE"
CDS_LMAN_SYM_OUTLINE"-300,700,250,-650"
CDS_LIB"pure_quanta"
$SEC"1"
CDS_SEC"1";
"PGND2"
$PN"7_9-20_24"14;
"GL2"
$PN"41"0;
"GL1"
$PN"6"0;
"DNC"
$PN"31"0;
"EN"
$PN"35"29;
"PGND3"
$PN"40"14;
"VOS"
$PN"1"26;
"VIN2"
$PN"30"5;
"PGND1"
$PN"5"14;
"SW"
$PN"10_19"27;
"LSET"
$PN"37"45;
"IOUT"
$PN"38"31;
"TOUT_FLT"
$PN"36"30;
"PVCC"
$PN"4"2;
"PHASE"
$PN"32"28;
"VIN1"
$PN"25_29"5;
"BOOT"
$PN"33"25;
"AGND"
$PN"2"14;
"VCC"
$PN"3"29;
"REFIN"
$PN"39"32;
"PWM"
$PN"34"39;
%"UNIVERSAL_GND"
"1","(5950,-1050)","0","logical_power","I24";
;
CDS_LIB"logical_power"
HDL_POWER"GND";
"A"13;
%"Q_CAP"
"1","(7275,-50)","2","pure_quanta","I26";
;
PART_NUMBER"CH4106K1B01"
MATERIAL"X7R"
TOLERANCE"10%"
VALUE"100NF"
VOLTAGE"50V"
PACK_TYPE"C0402"
LOCATION"PC509"
CDS_LIB"pure_quanta"
$SEC"1"
CDS_SEC"1";
"B"
$PN"2"37;
"A"
$PN"1"33;
%"Q_RES"
"1","(7850,-900)","0","pure_quanta","I27";
;
PART_NUMBER"CS00002JB13"
WATTAGE"1/16W"
MATERIAL"CHIP"
TOLERANCE"5%"
VALUE"0"
PACK_TYPE"0402LF"
LOCATION"PR295"
CDS_LIB"pure_quanta"
$SEC"1"
CDS_SEC"1";
"B"
$PN"2"4;
"A"
$PN"1"36;
%"Q_INDUCTOR4P_14"
"1","(7800,-450)","0","pure_quanta","I28";
;
PART_NUMBER"CV+15^0TZ04"
VALUE"150NH"
MATERIAL"IND"
PART_TYPE"SMLF"
LOCATION"PL26"
SEC_TYPE""
CDS_LIB"pure_quanta"
NEEDS_NO_SIZE"TRUE"
SEC"1";
"1"
$PN"1"38;
"4"
$PN"4"4;
"3"
$PN"3"22;
"2"
$PN"2"35;
%"Q_CAP"
"1","(6100,575)","0","pure_quanta","I29";
;
PART_NUMBER"TMP_QCH2336K1B12"
MATERIAL"X7R"
TOLERANCE"10%"
VALUE"3300PF"
VOLTAGE"50V"
PACK_TYPE"0402"
LOCATION"PC505_P1_6"
CDS_LIB"pure_quanta"
LOCATION"PC505_P1_6"
$SEC"1"
CDS_SEC"1";
"B"
$PN"2"17;
"A"
$PN"1"3;
%"Q_RES"
"1","(6550,125)","0","pure_quanta","I30";
;
PART_NUMBER"CS-3302FB01"
WATTAGE"1/16W"
MATERIAL"CHIP"
TOLERANCE"1%"
VALUE"3.3"
PACK_TYPE"0402LF"
LOCATION"PR1790"
CDS_LIB"pure_quanta"
$SEC"1"
CDS_SEC"1";
"B"
$PN"2"33;
"A"
$PN"1"34;
%"Q_CAP"
"1","(6500,575)","0","pure_quanta","I31";
;
PART_NUMBER"CH5103KEB01"
TOLERANCE"10%"
VALUE"1UF"
VOLTAGE"16V"
PACK_TYPE"C0402"
MATERIAL"X6S"
LOCATION"PC507_P1_6"
CDS_LIB"pure_quanta"
LOCATION"PC507_P1_6"
$SEC"1"
CDS_SEC"1";
"B"
$PN"2"17;
"A"
$PN"1"3;
%"UNIVERSAL_GND"
"1","(5975,1775)","0","logical_power","I32";
;
CDS_LIB"logical_power"
HDL_POWER"GND";
"A"14;
%"Q_CAP"
"1","(6900,575)","0","pure_quanta","I33";
;
PART_NUMBER"CH6223MEA01"
MATERIAL"X6S"
TOLERANCE"20%"
VALUE"22UF"
VOLTAGE"16V"
PACK_TYPE"C0805"
LOCATION"PC511_P1_6"
CDS_LIB"pure_quanta"
LOCATION"PC511_P1_6"
$SEC"1"
CDS_SEC"1";
"B"
$PN"2"17;
"A"
$PN"1"3;
%"Q_CAP"
"1","(7300,575)","0","pure_quanta","I34";
;
PART_NUMBER"CH6223MEA01"
MATERIAL"X6S"
TOLERANCE"20%"
VALUE"22UF"
VOLTAGE"16V"
PACK_TYPE"C0805"
LOCATION"PC513_P1_6"
CDS_LIB"pure_quanta"
LOCATION"PC513_P1_6"
$SEC"1"
CDS_SEC"1";
"B"
$PN"2"17;
"A"
$PN"1"3;
%"Q_CAP"
"1","(7675,575)","0","pure_quanta","I35";
;
PART_NUMBER"CH6223MEA01"
MATERIAL"X6S"
TOLERANCE"20%"
VALUE"22UF"
VOLTAGE"16V"
PACK_TYPE"C0805"
LOCATION"PC515_P1_6"
CDS_LIB"pure_quanta"
LOCATION"PC515_P1_6"
$SEC"1"
CDS_SEC"1";
"B"
$PN"2"17;
"A"
$PN"1"3;
%"Q_CAP"
"2","(4125,2300)","0","pure_quanta","I36";
;
PART_NUMBER"CH4104K1B00"
MATERIAL"X7R"
TOLERANCE"10%"
VALUE"0.1UF"
VOLTAGE"25V"
PACK_TYPE"0402"
LOCATION"PC1361"
CDS_LIB"pure_quanta"
$SEC"1"
CDS_SEC"1";
"A"
$PN"1"10;
"B"
$PN"2"32;
%"Q_CAP"
"1","(3800,3000)","0","pure_quanta","I37";
;
PART_NUMBER"CH5222KEB01"
MATERIAL"X6S"
TOLERANCE"10%"
VALUE"2.2UF"
VOLTAGE"10V"
PACK_TYPE"C0402"
LOCATION"PC502"
CDS_LIB"pure_quanta"
LOCATION"PC502"
$SEC"1"
CDS_SEC"1";
"B"
$PN"2"15;
"A"
$PN"1"29;
%"UNIVERSAL_GND"
"1","(3800,2750)","0","logical_power","I38";
;
CDS_LIB"logical_power"
HDL_POWER"GND";
"A"15;
%"Q_RES"
"2","(3800,3500)","0","pure_quanta","I39";
;
PART_NUMBER"CS-2202FB01"
WATTAGE"1/16W"
MATERIAL"CHIP"
TOLERANCE"1%"
VALUE"2.2"
PACK_TYPE"0402LF"
LOCATION"PR294"
CDS_LIB"pure_quanta"
LOCATION"PR294"
$SEC"1"
CDS_SEC"1";
"A"
$PN"1"2;
"B"
$PN"2"29;
%"UNIVERSAL_GND"
"1","(3275,-600)","0","logical_power","I4";
;
CDS_LIB"logical_power"
HDL_POWER"GND";
"A"8;
%"UNIVERSAL_GND"
"1","(4225,3275)","0","logical_power","I40";
;
CDS_LIB"logical_power"
HDL_POWER"GND";
"A"16;
%"Q_CAP"
"1","(4225,3500)","0","pure_quanta","I41";
;
PART_NUMBER"CH5222KEB01"
MATERIAL"X6S"
TOLERANCE"10%"
VALUE"2.2UF"
VOLTAGE"10V"
PACK_TYPE"C0402"
LOCATION"PC504_P1_5"
CDS_LIB"pure_quanta"
LOCATION"PC504_P1_5"
$SEC"1"
CDS_SEC"1";
"B"
$PN"2"16;
"A"
$PN"1"2;
%"VCC15"
"1","(3800,3825)","0","logical_power","I42";
;
HDL_POWER"PVCCIN_CPU1_PVCC"
CDS_LIB"logical_power";
"A"2;
%"Q_RES"
"1","(6575,2950)","0","pure_quanta","I44";
;
PART_NUMBER"CS-3302FB01"
WATTAGE"1/16W"
MATERIAL"CHIP"
TOLERANCE"1%"
VALUE"3.3"
PACK_TYPE"0402LF"
LOCATION"PR1791"
CDS_LIB"pure_quanta"
$SEC"1"
CDS_SEC"1";
"B"
$PN"2"24;
"A"
$PN"1"25;
%"Q_CAP"
"1","(6125,3400)","0","pure_quanta","I45";
;
PART_NUMBER"TMP_QCH2336K1B12"
MATERIAL"X7R"
TOLERANCE"10%"
VALUE"3300PF"
VOLTAGE"50V"
PACK_TYPE"0402"
LOCATION"PC506_P1_5"
CDS_LIB"pure_quanta"
LOCATION"PC506_P1_5"
$SEC"1"
CDS_SEC"1";
"B"
$PN"2"20;
"A"
$PN"1"5;
%"Q_CAP"
"1","(6525,3400)","0","pure_quanta","I46";
;
PART_NUMBER"CH5103KEB01"
MATERIAL"X6S"
TOLERANCE"10%"
VALUE"1UF"
VOLTAGE"16V"
PACK_TYPE"C0402"
LOCATION"PC508_P1_5"
CDS_LIB"pure_quanta"
LOCATION"PC508_P1_5"
$SEC"1"
CDS_SEC"1";
"B"
$PN"2"20;
"A"
$PN"1"5;
%"Q_CAP"
"1","(7300,2775)","2","pure_quanta","I47";
;
PART_NUMBER"CH4106K1B01"
MATERIAL"X7R"
TOLERANCE"10%"
PACK_TYPE"C0402"
VALUE"100NF"
VOLTAGE"50V"
LOCATION"PC510"
CDS_LIB"pure_quanta"
$SEC"1"
CDS_SEC"1";
"B"
$PN"2"28;
"A"
$PN"1"24;
%"Q_INDUCTOR4P_14"
"1","(7775,2375)","0","pure_quanta","I48";
;
PART_NUMBER"CV+15^0TZ04"
MATERIAL"IND"
VALUE"150NH"
PART_TYPE"SMLF"
LOCATION"PL27"
NEEDS_NO_SIZE"TRUE"
CDS_LIB"pure_quanta"
SEC_TYPE""
SEC"1";
"1"
$PN"1"27;
"4"
$PN"4"6;
"3"
$PN"3"21;
"2"
$PN"2"23;
%"Q_RES"
"1","(7900,1975)","0","pure_quanta","I49";
;
PART_NUMBER"CS00002JB13"
MATERIAL"CHIP"
TOLERANCE"5%"
VALUE"0"
WATTAGE"1/16W"
PACK_TYPE"0402LF"
LOCATION"PR296"
CDS_LIB"pure_quanta"
$SEC"1"
CDS_SEC"1";
"B"
$PN"2"6;
"A"
$PN"1"26;
%"Q_CAP"
"1","(6925,3400)","0","pure_quanta","I50";
;
PART_NUMBER"CH6223MEA01"
MATERIAL"X6S"
TOLERANCE"20%"
VALUE"22UF"
VOLTAGE"16V"
PACK_TYPE"C0805"
LOCATION"PC512_P1_5"
CDS_LIB"pure_quanta"
LOCATION"PC512_P1_5"
$SEC"1"
CDS_SEC"1";
"B"
$PN"2"20;
"A"
$PN"1"5;
%"Q_CAP"
"1","(7325,3400)","0","pure_quanta","I51";
;
PART_NUMBER"CH6223MEA01"
MATERIAL"X6S"
TOLERANCE"20%"
VALUE"22UF"
VOLTAGE"16V"
PACK_TYPE"C0805"
LOCATION"PC514_P1_5"
CDS_LIB"pure_quanta"
LOCATION"PC514_P1_5"
$SEC"1"
CDS_SEC"1";
"B"
$PN"2"20;
"A"
$PN"1"5;
%"Q_CAP"
"1","(7700,3400)","0","pure_quanta","I52";
;
PART_NUMBER"CH6223MEA01"
MATERIAL"X6S"
TOLERANCE"20%"
VALUE"22UF"
VOLTAGE"16V"
PACK_TYPE"C0805"
LOCATION"PC516_P1_5"
CDS_LIB"pure_quanta"
LOCATION"PC516_P1_5"
$SEC"1"
CDS_SEC"1";
"B"
$PN"2"20;
"A"
$PN"1"5;
%"Q_CAP"
"1","(9675,-525)","0","pure_quanta","I54";
;
PART_NUMBER"CH622KMEA03"
PACK_TYPE"C0805"
VOLTAGE"4V"
VALUE"22UF"
TOLERANCE"20%"
MATERIAL"X6S"
LOCATION"PC519_P1_6"
CDS_LIB"pure_quanta"
LOCATION"PC519_P1_6"
$SEC"1"
CDS_SEC"1";
"B"
$PN"2"18;
"A"
$PN"1"4;
%"UNIVERSAL_GND"
"1","(7900,150)","0","logical_power","I55";
;
CDS_LIB"logical_power"
HDL_POWER"GND";
"A"17;
%"VCC15"
"1","(7900,950)","0","logical_power","I56";
;
HDL_POWER"SW_P12V_PVCCIN_CPU1_FLT"
CDS_LIB"logical_power";
"A"3;
%"Q_CAP"
"1","(10100,-525)","0","pure_quanta","I57";
;
PART_NUMBER"CH622KMEA03"
PACK_TYPE"C0805"
VOLTAGE"4V"
VALUE"22UF"
TOLERANCE"20%"
MATERIAL"X6S"
LOCATION"PC521_P1_6"
CDS_LIB"pure_quanta"
LOCATION"PC521_P1_6"
$SEC"1"
CDS_SEC"1";
"B"
$PN"2"18;
"A"
$PN"1"4;
%"UNIVERSAL_GND"
"1","(10400,-900)","0","logical_power","I58";
;
CDS_LIB"logical_power"
HDL_POWER"GND";
"A"18;
%"VCC15"
"1","(10400,-125)","0","logical_power","I59";
;
HDL_POWER"PVCCIN_CPU1"
CDS_LIB"logical_power";
"A"4;
%"UNIVERSAL_GND"
"1","(3400,1775)","0","logical_power","I6";
;
CDS_LIB"logical_power"
HDL_POWER"GND";
"A"9;
%"UNIVERSAL_GND"
"1","(10275,1925)","0","logical_power","I60";
;
CDS_LIB"logical_power"
HDL_POWER"GND";
"A"19;
%"UNIVERSAL_GND"
"1","(7925,2975)","0","logical_power","I61";
;
CDS_LIB"logical_power"
HDL_POWER"GND";
"A"20;
%"VCC15"
"1","(7925,3775)","0","logical_power","I63";
;
HDL_POWER"SW_P12V_PVCCIN_CPU1_FLT"
CDS_LIB"logical_power";
"A"5;
%"Q_CAP"
"1","(9550,2300)","0","pure_quanta","I64";
;
PART_NUMBER"CH622KMEA03"
PACK_TYPE"C0805"
VOLTAGE"4V"
VALUE"22UF"
TOLERANCE"20%"
MATERIAL"X6S"
LOCATION"PC520_P1_5"
CDS_LIB"pure_quanta"
LOCATION"PC520_P1_5"
$SEC"1"
CDS_SEC"1";
"B"
$PN"2"19;
"A"
$PN"1"6;
%"Q_CAP"
"1","(9975,2300)","0","pure_quanta","I65";
;
PART_NUMBER"CH622KMEA03"
PACK_TYPE"C0805"
VOLTAGE"4V"
VALUE"22UF"
TOLERANCE"20%"
MATERIAL"X6S"
LOCATION"PC522_P1_5"
CDS_LIB"pure_quanta"
LOCATION"PC522_P1_5"
$SEC"1"
CDS_SEC"1";
"B"
$PN"2"19;
"A"
$PN"1"6;
%"VCC15"
"1","(10275,2700)","0","logical_power","I66";
;
HDL_POWER"PVCCIN_CPU1"
CDS_LIB"logical_power";
"A"6;
%"Q_RES"
"2","(3400,2000)","2","pure_quanta","I7";
;
PART_NUMBER"CS28872FB01"
WATTAGE"1/16W"
TOLERANCE"1%"
VALUE"8.87K"
MATERIAL"EMPTY"
PACK_TYPE"0402LF"
LOCATION"PR292"
CDS_LIB"pure_quanta"
LOCATION"PR292"
$SEC"1"
CDS_SEC"1";
"A"
$PN"1"45;
"B"
$PN"2"9;
%"UNIVERSAL_GND"
"1","(3300,2225)","0","logical_power","I9";
;
CDS_LIB"logical_power"
HDL_POWER"GND";
"A"10;
END.
